# S9S_MB_2U (Grand Teton) — schematic netlist excerpt (pin names and nets, part order shuffled) for the footprints in the layout excerpt that follows; sources: Cadence DE-HDL packaged netlist, KiCad conversion of 03242023_DA0F0TMBIJ0_F0T_Motherboard_J_brd_V01_OCP.brd

R4509  Q_RES  33.2 1% CHIP  pkg 0402LF  page 240 : A = SMB_1_PLD_3V3AUX_SDA ; B = SMB_1_PLD_3V3AUX_SDA_R3
PL105  Q_INDUCTOR  120NH/69A IND  pkg SMLF  page 270 : \1\ = IND_P0_CPL7 ; \2\ = GND

(kicad_pcb
	(version 20260206)
	(generator "pcbnew")
	(generator_version "10.0")
	(general
		(thickness 1.6)
		(legacy_teardrops no)
	)
	(paper "A4")
	(title_block
		(title "03242023_DA0F0TMBIJ0_F0T_Motherboard_J_brd_V01_OCP.brd")
		(comment 1 "Grand Teton / footprints 3269-3270 of 6105")
	)
	(layers
		(0 "F.Cu" signal "TOP")
		(4 "In1.Cu" signal "GND")
		(6 "In2.Cu" signal "IN1")
		(8 "In3.Cu" signal "GND1")
		(10 "In4.Cu" signal "IN2")
		(12 "In5.Cu" signal "GND2")
		(14 "In6.Cu" signal "IN3")
		(16 "In7.Cu" signal "GND3")
		(18 "In8.Cu" signal "VCC")
		(20 "In9.Cu" signal "VCC1")
		(22 "In10.Cu" signal "GND4")
		(24 "In11.Cu" signal "IN4")
		(26 "In12.Cu" signal "GND5")
		(28 "In13.Cu" signal "IN5")
		(30 "In14.Cu" signal "GND6")
		(32 "In15.Cu" signal "IN6")
		(34 "In16.Cu" signal "GND7")
		(2 "B.Cu" signal "BOTTOM")
		(9 "F.Adhes" user "F.Adhesive")
		(11 "B.Adhes" user "B.Adhesive")
		(13 "F.Paste" user "Package Geometry/Pastemask Top")
		(15 "B.Paste" user "Package Geometry/Pastemask Bottom")
		(5 "F.SilkS" user "Ref Des/Silkscreen Top")
		(7 "B.SilkS" user "Ref Des/Silkscreen Bottom")
		(1 "F.Mask" user "Board Geometry/Soldermask Top")
		(3 "B.Mask" user "Board Geometry/Soldermask Bottom")
		(17 "Dwgs.User" user "User.Drawings")
		(19 "Cmts.User" user "User.Comments")
		(21 "Eco1.User" user "User.Eco1")
		(23 "Eco2.User" user "User.Eco2")
		(25 "Edge.Cuts" user "Board Geometry/Outline")
		(27 "Margin" user)
		(31 "F.CrtYd" user "Package Geometry/Place Bound Top")
		(29 "B.CrtYd" user "Package Geometry/Place Bound Bottom")
		(35 "F.Fab" user "Ref Des/Assembly Top")
		(33 "B.Fab" user "Ref Des/Assembly Bottom")
	)
	(footprint ""
		(layer "F.Cu")
		(at 320.95567 -338.218526 90)
		(property "Reference" "PL105"
			(at -4.399788 -2.95021 0)
			(unlocked yes)
			(layer "F.SilkS")
			(effects
				(font
					(size 0.7874 0.5842)
					(thickness 0.1524)
				)
				(justify left)
			)
		)
		(property "Value" ""
			(at 0 0 90)
			(layer "F.Fab")
			(effects
				(font
					(size 1.27 1.27)
				)
			)
		)
		(duplicate_pad_numbers_are_jumpers no)
		(fp_line
			(start 3.24993 -3.24993)
			(end 3.24993 -2.2352)
			(stroke
				(width 0.1524)
				(type default)
			)
			(layer "F.SilkS")
		)
		(fp_line
			(start -3.24993 -3.24993)
			(end 3.24993 -3.24993)
			(stroke
				(width 0.1524)
				(type default)
			)
			(layer "F.SilkS")
		)
		(fp_line
			(start -3.24993 -2.2352)
			(end -3.24993 -3.24993)
			(stroke
				(width 0.1524)
				(type default)
			)
			(layer "F.SilkS")
		)
		(fp_line
			(start 3.24993 2.2352)
			(end 3.24993 3.24993)
			(stroke
				(width 0.1524)
				(type default)
			)
			(layer "F.SilkS")
		)
		(fp_line
			(start 3.24993 3.24993)
			(end 0.201422 3.24993)
			(stroke
				(width 0.1524)
				(type default)
			)
			(layer "F.SilkS")
		)
		(fp_line
			(start -0.814578 3.24993)
			(end -3.24993 3.24993)
			(stroke
				(width 0.1524)
				(type default)
			)
			(layer "F.SilkS")
		)
		(fp_line
			(start -3.24993 3.24993)
			(end -3.24993 2.2352)
			(stroke
				(width 0.1524)
				(type default)
			)
			(layer "F.SilkS")
		)
		(fp_line
			(start 3.24993 -3.24993)
			(end 3.24993 3.24993)
			(stroke
				(width 0.1)
				(type default)
			)
			(layer "F.Fab")
		)
		(fp_line
			(start -3.24993 -3.24993)
			(end 3.24993 -3.24993)
			(stroke
				(width 0.1)
				(type default)
			)
			(layer "F.Fab")
		)
		(fp_line
			(start 3.24993 3.24993)
			(end -3.24993 3.24993)
			(stroke
				(width 0.1)
				(type default)
			)
			(layer "F.Fab")
		)
		(fp_line
			(start -3.24993 3.24993)
			(end -3.24993 -3.24993)
			(stroke
				(width 0.1)
				(type default)
			)
			(layer "F.Fab")
		)
		(pad "1" smd rect
			(at -2.29997 0 90)
			(size 2.0066 4.2164)
			(layers "F.Cu" "F.Mask" "F.Paste")
			(net "IND_P0_CPL7")
		)
		(pad "2" smd rect
			(at 2.29997 0 90)
			(size 2.0066 4.2164)
			(layers "F.Cu" "F.Mask" "F.Paste")
			(net "GND")
		)
	)
	(footprint ""
		(layer "F.Cu")
		(at 161.163 -20.665948 -90)
		(property "Reference" "R4509"
			(at 0 0 270)
			(layer "F.SilkS")
			(hide yes)
			(effects
				(font
					(size 1.27 1.27)
				)
			)
		)
		(property "Value" ""
			(at 0 0 270)
			(layer "F.Fab")
			(effects
				(font
					(size 1.27 1.27)
				)
			)
		)
		(duplicate_pad_numbers_are_jumpers no)
		(fp_line
			(start -0.7874 0.4064)
			(end -0.7874 -0.4064)
			(stroke
				(width 0.1524)
				(type default)
			)
			(layer "F.SilkS")
		)
		(fp_line
			(start 0.7874 0.4064)
			(end -0.7874 0.4064)
			(stroke
				(width 0.1524)
				(type default)
			)
			(layer "F.SilkS")
		)
		(fp_line
			(start -0.7874 -0.4064)
			(end 0.7874 -0.4064)
			(stroke
				(width 0.1524)
				(type default)
			)
			(layer "F.SilkS")
		)
		(fp_line
			(start 0.7874 -0.4064)
			(end 0.7874 0.4064)
			(stroke
				(width 0.1524)
				(type default)
			)
			(layer "F.SilkS")
		)
		(fp_line
			(start -0.67945 0.3048)
			(end -0.67945 -0.305054)
			(stroke
				(width 0.1)
				(type default)
			)
			(layer "F.Fab")
		)
		(fp_line
			(start -0.12065 0.3048)
			(end -0.67945 0.3048)
			(stroke
				(width 0.1)
				(type default)
			)
			(layer "F.Fab")
		)
		(fp_line
			(start 0.120396 0.3048)
			(end 0.120396 0.2794)
			(stroke
				(width 0.1)
				(type default)
			)
			(layer "F.Fab")
		)
		(fp_line
			(start 0.67945 0.3048)
			(end 0.120396 0.3048)
			(stroke
				(width 0.1)
				(type default)
			)
			(layer "F.Fab")
		)
		(fp_line
			(start -0.12065 0.2794)
			(end -0.12065 0.3048)
			(stroke
				(width 0.1)
				(type default)
			)
			(layer "F.Fab")
		)
		(fp_line
			(start 0.120396 0.2794)
			(end -0.12065 0.2794)
			(stroke
				(width 0.1)
				(type default)
			)
			(layer "F.Fab")
		)
		(fp_line
			(start -0.12065 -0.2794)
			(end 0.12065 -0.2794)
			(stroke
				(width 0.1)
				(type default)
			)
			(layer "F.Fab")
		)
		(fp_line
			(start 0.12065 -0.2794)
			(end 0.12065 -0.3048)
			(stroke
				(width 0.1)
				(type default)
			)
			(layer "F.Fab")
		)
		(fp_line
			(start 0.12065 -0.3048)
			(end 0.67945 -0.3048)
			(stroke
				(width 0.1)
				(type default)
			)
			(layer "F.Fab")
		)
		(fp_line
			(start 0.67945 -0.3048)
			(end 0.67945 0.3048)
			(stroke
				(width 0.1)
				(type default)
			)
			(layer "F.Fab")
		)
		(fp_line
			(start -0.67945 -0.305054)
			(end -0.12065 -0.305054)
			(stroke
				(width 0.1)
				(type default)
			)
			(layer "F.Fab")
		)
		(fp_line
			(start -0.12065 -0.305054)
			(end -0.12065 -0.2794)
			(stroke
				(width 0.1)
				(type default)
			)
			(layer "F.Fab")
		)
		(pad "1" smd circle
			(at -0.40005 0 270)
			(size 0 0)
			(layers "F.Cu" "F.Mask" "F.Paste")
			(net "SMB_1_PLD_3V3AUX_SDA")
		)
		(pad "2" smd circle
			(at 0.40005 0 270)
			(size 0 0)
			(layers "F.Cu" "F.Mask" "F.Paste")
			(net "SMB_1_PLD_3V3AUX_SDA_R3")
		)
	)
)
